(kicad_pcb
	(version 20260206)
	(generator "pcbnew")
	(generator_version "10.0")
	(general
		(thickness 1.6)
		(legacy_teardrops no)
	)
	(paper "A4")
	(title_block
		(title "01162023_DA0F0TEBIF0_F0T_Expander_BD_F_brd_V02_OCP.brd")
		(comment 1 "Grand Teton / footprints 705-712 of 9728")
	)
	(layers
		(0 "F.Cu" signal "TOP")
		(4 "In1.Cu" signal "GND")
		(6 "In2.Cu" signal "VCC")
		(8 "In3.Cu" signal "VCC1")
		(10 "In4.Cu" signal "GND1")
		(12 "In5.Cu" signal "IN1")
		(14 "In6.Cu" signal "GND2")
		(16 "In7.Cu" signal "IN2")
		(18 "In8.Cu" signal "GND3")
		(20 "In9.Cu" signal "IN3")
		(22 "In10.Cu" signal "GND4")
		(24 "In11.Cu" signal "IN4")
		(26 "In12.Cu" signal "GND5")
		(28 "In13.Cu" signal "IN5")
		(30 "In14.Cu" signal "GND6")
		(32 "In15.Cu" signal "IN6")
		(34 "In16.Cu" signal "GND7")
		(2 "B.Cu" signal "BOTTOM")
		(9 "F.Adhes" user "F.Adhesive")
		(11 "B.Adhes" user "B.Adhesive")
		(13 "F.Paste" user "Package Geometry/Pastemask Top")
		(15 "B.Paste" user "Package Geometry/Pastemask Bottom")
		(5 "F.SilkS" user "Ref Des/Silkscreen Top")
		(7 "B.SilkS" user "Ref Des/Silkscreen Bottom")
		(1 "F.Mask" user "Board Geometry/Soldermask Top")
		(3 "B.Mask" user "Board Geometry/Soldermask Bottom")
		(17 "Dwgs.User" user "User.Drawings")
		(19 "Cmts.User" user "User.Comments")
		(21 "Eco1.User" user "User.Eco1")
		(23 "Eco2.User" user "User.Eco2")
		(25 "Edge.Cuts" user "Board Geometry/Outline")
		(27 "Margin" user)
		(31 "F.CrtYd" user "Package Geometry/Place Bound Top")
		(29 "B.CrtYd" user "Package Geometry/Place Bound Bottom")
		(35 "F.Fab" user "Ref Des/Assembly Top")
		(33 "B.Fab" user "Ref Des/Assembly Bottom")
	)
	(footprint ""
		(layer "F.Cu")
		(at 363.207808 -154.510994)
		(property "Reference" "PC820"
			(at 0 0 0)
			(layer "F.SilkS")
			(hide yes)
			(effects
				(font
					(size 1.27 1.27)
				)
			)
		)
		(property "Value" ""
			(at 0 0 0)
			(layer "F.Fab")
			(effects
				(font
					(size 1.27 1.27)
				)
			)
		)
		(duplicate_pad_numbers_are_jumpers no)
		(fp_line
			(start -0.7874 -0.4064)
			(end 0.7874 -0.4064)
			(stroke
				(width 0.1524)
				(type default)
			)
			(layer "F.SilkS")
		)
		(fp_line
			(start -0.7874 0.4064)
			(end -0.7874 -0.4064)
			(stroke
				(width 0.1524)
				(type default)
			)
			(layer "F.SilkS")
		)
		(fp_line
			(start 0.7874 -0.4064)
			(end 0.7874 0.4064)
			(stroke
				(width 0.1524)
				(type default)
			)
			(layer "F.SilkS")
		)
		(fp_line
			(start 0.7874 0.4064)
			(end -0.7874 0.4064)
			(stroke
				(width 0.1524)
				(type default)
			)
			(layer "F.SilkS")
		)
		(fp_line
			(start -0.67945 -0.305054)
			(end -0.12065 -0.305054)
			(stroke
				(width 0.1)
				(type default)
			)
			(layer "F.Fab")
		)
		(fp_line
			(start -0.67945 0.3048)
			(end -0.67945 -0.305054)
			(stroke
				(width 0.1)
				(type default)
			)
			(layer "F.Fab")
		)
		(fp_line
			(start -0.12065 -0.305054)
			(end -0.12065 -0.2794)
			(stroke
				(width 0.1)
				(type default)
			)
			(layer "F.Fab")
		)
		(fp_line
			(start -0.12065 -0.2794)
			(end 0.12065 -0.2794)
			(stroke
				(width 0.1)
				(type default)
			)
			(layer "F.Fab")
		)
		(fp_line
			(start -0.12065 0.2794)
			(end -0.12065 0.3048)
			(stroke
				(width 0.1)
				(type default)
			)
			(layer "F.Fab")
		)
		(fp_line
			(start -0.12065 0.3048)
			(end -0.67945 0.3048)
			(stroke
				(width 0.1)
				(type default)
			)
			(layer "F.Fab")
		)
		(fp_line
			(start 0.120396 0.2794)
			(end -0.12065 0.2794)
			(stroke
				(width 0.1)
				(type default)
			)
			(layer "F.Fab")
		)
		(fp_line
			(start 0.120396 0.3048)
			(end 0.120396 0.2794)
			(stroke
				(width 0.1)
				(type default)
			)
			(layer "F.Fab")
		)
		(fp_line
			(start 0.12065 -0.3048)
			(end 0.67945 -0.3048)
			(stroke
				(width 0.1)
				(type default)
			)
			(layer "F.Fab")
		)
		(fp_line
			(start 0.12065 -0.2794)
			(end 0.12065 -0.3048)
			(stroke
				(width 0.1)
				(type default)
			)
			(layer "F.Fab")
		)
		(fp_line
			(start 0.67945 -0.3048)
			(end 0.67945 0.3048)
			(stroke
				(width 0.1)
				(type default)
			)
			(layer "F.Fab")
		)
		(fp_line
			(start 0.67945 0.3048)
			(end 0.120396 0.3048)
			(stroke
				(width 0.1)
				(type default)
			)
			(layer "F.Fab")
		)
		(pad "1" smd circle
			(at -0.40005 0)
			(size 0 0)
			(layers "F.Cu" "F.Mask" "F.Paste")
			(net "P12V_NIC6_R")
		)
		(pad "2" smd circle
			(at 0.40005 0)
			(size 0 0)
			(layers "F.Cu" "F.Mask" "F.Paste")
			(net "GND")
		)
	)
	(footprint ""
		(layer "F.Cu")
		(at 102.900734 -237.306612 90)
		(property "Reference" "PC291"
			(at 0 0 90)
			(layer "F.SilkS")
			(hide yes)
			(effects
				(font
					(size 1.27 1.27)
				)
			)
		)
		(property "Value" ""
			(at 0 0 90)
			(layer "F.Fab")
			(effects
				(font
					(size 1.27 1.27)
				)
			)
		)
		(duplicate_pad_numbers_are_jumpers no)
		(fp_line
			(start 1.524 -0.762)
			(end 1.524 0.762)
			(stroke
				(width 0.1524)
				(type default)
			)
			(layer "F.SilkS")
		)
		(fp_line
			(start -1.524 -0.762)
			(end 1.524 -0.762)
			(stroke
				(width 0.1524)
				(type default)
			)
			(layer "F.SilkS")
		)
		(fp_line
			(start 1.524 0.762)
			(end -1.524 0.762)
			(stroke
				(width 0.1524)
				(type default)
			)
			(layer "F.SilkS")
		)
		(fp_line
			(start -1.524 0.762)
			(end -1.524 -0.762)
			(stroke
				(width 0.1524)
				(type default)
			)
			(layer "F.SilkS")
		)
		(fp_line
			(start 1.1049 -0.724916)
			(end -1.1049 -0.724916)
			(stroke
				(width 0.1)
				(type default)
			)
			(layer "F.Fab")
		)
		(fp_line
			(start -1.1049 -0.724916)
			(end -1.1049 0.724916)
			(stroke
				(width 0.1)
				(type default)
			)
			(layer "F.Fab")
		)
		(fp_line
			(start 1.1049 0.724916)
			(end 1.1049 -0.724916)
			(stroke
				(width 0.1)
				(type default)
			)
			(layer "F.Fab")
		)
		(fp_line
			(start -1.1049 0.724916)
			(end 1.1049 0.724916)
			(stroke
				(width 0.1)
				(type default)
			)
			(layer "F.Fab")
		)
		(pad "1" smd rect
			(at -0.889 0 270)
			(size 1.016 1.27)
			(layers "F.Cu" "F.Mask" "F.Paste")
			(net "P1V8_PEX_R")
		)
		(pad "2" smd rect
			(at 0.889 0 270)
			(size 1.016 1.27)
			(layers "F.Cu" "F.Mask" "F.Paste")
			(net "GND")
		)
	)
	(footprint ""
		(layer "F.Cu")
		(at 295.52519 -213.523068 -90)
		(property "Reference" "R3396"
			(at 0 0 270)
			(layer "F.SilkS")
			(hide yes)
			(effects
				(font
					(size 1.27 1.27)
				)
			)
		)
		(property "Value" ""
			(at 0 0 270)
			(layer "F.Fab")
			(effects
				(font
					(size 1.27 1.27)
				)
			)
		)
		(duplicate_pad_numbers_are_jumpers no)
		(fp_line
			(start -0.7874 0.4064)
			(end -0.7874 -0.4064)
			(stroke
				(width 0.1524)
				(type default)
			)
			(layer "F.SilkS")
		)
		(fp_line
			(start 0.7874 0.4064)
			(end -0.7874 0.4064)
			(stroke
				(width 0.1524)
				(type default)
			)
			(layer "F.SilkS")
		)
		(fp_line
			(start -0.7874 -0.4064)
			(end 0.7874 -0.4064)
			(stroke
				(width 0.1524)
				(type default)
			)
			(layer "F.SilkS")
		)
		(fp_line
			(start 0.7874 -0.4064)
			(end 0.7874 0.4064)
			(stroke
				(width 0.1524)
				(type default)
			)
			(layer "F.SilkS")
		)
		(fp_line
			(start -0.67945 0.3048)
			(end -0.67945 -0.305054)
			(stroke
				(width 0.1)
				(type default)
			)
			(layer "F.Fab")
		)
		(fp_line
			(start -0.12065 0.3048)
			(end -0.67945 0.3048)
			(stroke
				(width 0.1)
				(type default)
			)
			(layer "F.Fab")
		)
		(fp_line
			(start 0.120396 0.3048)
			(end 0.120396 0.2794)
			(stroke
				(width 0.1)
				(type default)
			)
			(layer "F.Fab")
		)
		(fp_line
			(start 0.67945 0.3048)
			(end 0.120396 0.3048)
			(stroke
				(width 0.1)
				(type default)
			)
			(layer "F.Fab")
		)
		(fp_line
			(start -0.12065 0.2794)
			(end -0.12065 0.3048)
			(stroke
				(width 0.1)
				(type default)
			)
			(layer "F.Fab")
		)
		(fp_line
			(start 0.120396 0.2794)
			(end -0.12065 0.2794)
			(stroke
				(width 0.1)
				(type default)
			)
			(layer "F.Fab")
		)
		(fp_line
			(start -0.12065 -0.2794)
			(end 0.12065 -0.2794)
			(stroke
				(width 0.1)
				(type default)
			)
			(layer "F.Fab")
		)
		(fp_line
			(start 0.12065 -0.2794)
			(end 0.12065 -0.3048)
			(stroke
				(width 0.1)
				(type default)
			)
			(layer "F.Fab")
		)
		(fp_line
			(start 0.12065 -0.3048)
			(end 0.67945 -0.3048)
			(stroke
				(width 0.1)
				(type default)
			)
			(layer "F.Fab")
		)
		(fp_line
			(start 0.67945 -0.3048)
			(end 0.67945 0.3048)
			(stroke
				(width 0.1)
				(type default)
			)
			(layer "F.Fab")
		)
		(fp_line
			(start -0.67945 -0.305054)
			(end -0.12065 -0.305054)
			(stroke
				(width 0.1)
				(type default)
			)
			(layer "F.Fab")
		)
		(fp_line
			(start -0.12065 -0.305054)
			(end -0.12065 -0.2794)
			(stroke
				(width 0.1)
				(type default)
			)
			(layer "F.Fab")
		)
		(pad "1" smd circle
			(at -0.40005 0 270)
			(size 0 0)
			(layers "F.Cu" "F.Mask" "F.Paste")
			(net "SPI_BIC1_MOSI_LS23_R1")
		)
		(pad "2" smd circle
			(at 0.40005 0 270)
			(size 0 0)
			(layers "F.Cu" "F.Mask" "F.Paste")
			(net "SPI_BIC1_MOSI_LS23_R")
		)
	)
	(footprint ""
		(layer "F.Cu")
		(at 127.658114 -261.814564 180)
		(property "Reference" "C832"
			(at 0 0 180)
			(layer "F.SilkS")
			(hide yes)
			(effects
				(font
					(size 1.27 1.27)
				)
			)
		)
		(property "Value" ""
			(at 0 0 180)
			(layer "F.Fab")
			(effects
				(font
					(size 1.27 1.27)
				)
			)
		)
		(duplicate_pad_numbers_are_jumpers no)
		(fp_line
			(start 0.7874 0.4064)
			(end -0.7874 0.4064)
			(stroke
				(width 0.1524)
				(type default)
			)
			(layer "F.SilkS")
		)
		(fp_line
			(start 0.7874 -0.4064)
			(end 0.7874 0.4064)
			(stroke
				(width 0.1524)
				(type default)
			)
			(layer "F.SilkS")
		)
		(fp_line
			(start -0.7874 0.4064)
			(end -0.7874 -0.4064)
			(stroke
				(width 0.1524)
				(type default)
			)
			(layer "F.SilkS")
		)
		(fp_line
			(start -0.7874 -0.4064)
			(end 0.7874 -0.4064)
			(stroke
				(width 0.1524)
				(type default)
			)
			(layer "F.SilkS")
		)
		(fp_line
			(start 0.67945 0.3048)
			(end 0.120396 0.3048)
			(stroke
				(width 0.1)
				(type default)
			)
			(layer "F.Fab")
		)
		(fp_line
			(start 0.67945 -0.3048)
			(end 0.67945 0.3048)
			(stroke
				(width 0.1)
				(type default)
			)
			(layer "F.Fab")
		)
		(fp_line
			(start 0.12065 -0.2794)
			(end 0.12065 -0.3048)
			(stroke
				(width 0.1)
				(type default)
			)
			(layer "F.Fab")
		)
		(fp_line
			(start 0.12065 -0.3048)
			(end 0.67945 -0.3048)
			(stroke
				(width 0.1)
				(type default)
			)
			(layer "F.Fab")
		)
		(fp_line
			(start 0.120396 0.3048)
			(end 0.120396 0.2794)
			(stroke
				(width 0.1)
				(type default)
			)
			(layer "F.Fab")
		)
		(fp_line
			(start 0.120396 0.2794)
			(end -0.12065 0.2794)
			(stroke
				(width 0.1)
				(type default)
			)
			(layer "F.Fab")
		)
		(fp_line
			(start -0.12065 0.3048)
			(end -0.67945 0.3048)
			(stroke
				(width 0.1)
				(type default)
			)
			(layer "F.Fab")
		)
		(fp_line
			(start -0.12065 0.2794)
			(end -0.12065 0.3048)
			(stroke
				(width 0.1)
				(type default)
			)
			(layer "F.Fab")
		)
		(fp_line
			(start -0.12065 -0.2794)
			(end 0.12065 -0.2794)
			(stroke
				(width 0.1)
				(type default)
			)
			(layer "F.Fab")
		)
		(fp_line
			(start -0.12065 -0.305054)
			(end -0.12065 -0.2794)
			(stroke
				(width 0.1)
				(type default)
			)
			(layer "F.Fab")
		)
		(fp_line
			(start -0.67945 0.3048)
			(end -0.67945 -0.305054)
			(stroke
				(width 0.1)
				(type default)
			)
			(layer "F.Fab")
		)
		(fp_line
			(start -0.67945 -0.305054)
			(end -0.12065 -0.305054)
			(stroke
				(width 0.1)
				(type default)
			)
			(layer "F.Fab")
		)
		(pad "1" smd circle
			(at -0.40005 0 180)
			(size 0 0)
			(layers "F.Cu" "F.Mask" "F.Paste")
			(net "GND")
		)
		(pad "2" smd circle
			(at 0.40005 0 180)
			(size 0 0)
			(layers "F.Cu" "F.Mask" "F.Paste")
			(net "FM_P0V8_PEX1_EN_R")
		)
	)
	(footprint ""
		(layer "F.Cu")
		(at 300.60519 -213.523068 -90)
		(property "Reference" "R3394"
			(at 0 0 270)
			(layer "F.SilkS")
			(hide yes)
			(effects
				(font
					(size 1.27 1.27)
				)
			)
		)
		(property "Value" ""
			(at 0 0 270)
			(layer "F.Fab")
			(effects
				(font
					(size 1.27 1.27)
				)
			)
		)
		(duplicate_pad_numbers_are_jumpers no)
		(fp_line
			(start -0.7874 0.4064)
			(end -0.7874 -0.4064)
			(stroke
				(width 0.1524)
				(type default)
			)
			(layer "F.SilkS")
		)
		(fp_line
			(start 0.7874 0.4064)
			(end -0.7874 0.4064)
			(stroke
				(width 0.1524)
				(type default)
			)
			(layer "F.SilkS")
		)
		(fp_line
			(start -0.7874 -0.4064)
			(end 0.7874 -0.4064)
			(stroke
				(width 0.1524)
				(type default)
			)
			(layer "F.SilkS")
		)
		(fp_line
			(start 0.7874 -0.4064)
			(end 0.7874 0.4064)
			(stroke
				(width 0.1524)
				(type default)
			)
			(layer "F.SilkS")
		)
		(fp_line
			(start -0.67945 0.3048)
			(end -0.67945 -0.305054)
			(stroke
				(width 0.1)
				(type default)
			)
			(layer "F.Fab")
		)
		(fp_line
			(start -0.12065 0.3048)
			(end -0.67945 0.3048)
			(stroke
				(width 0.1)
				(type default)
			)
			(layer "F.Fab")
		)
		(fp_line
			(start 0.120396 0.3048)
			(end 0.120396 0.2794)
			(stroke
				(width 0.1)
				(type default)
			)
			(layer "F.Fab")
		)
		(fp_line
			(start 0.67945 0.3048)
			(end 0.120396 0.3048)
			(stroke
				(width 0.1)
				(type default)
			)
			(layer "F.Fab")
		)
		(fp_line
			(start -0.12065 0.2794)
			(end -0.12065 0.3048)
			(stroke
				(width 0.1)
				(type default)
			)
			(layer "F.Fab")
		)
		(fp_line
			(start 0.120396 0.2794)
			(end -0.12065 0.2794)
			(stroke
				(width 0.1)
				(type default)
			)
			(layer "F.Fab")
		)
		(fp_line
			(start -0.12065 -0.2794)
			(end 0.12065 -0.2794)
			(stroke
				(width 0.1)
				(type default)
			)
			(layer "F.Fab")
		)
		(fp_line
			(start 0.12065 -0.2794)
			(end 0.12065 -0.3048)
			(stroke
				(width 0.1)
				(type default)
			)
			(layer "F.Fab")
		)
		(fp_line
			(start 0.12065 -0.3048)
			(end 0.67945 -0.3048)
			(stroke
				(width 0.1)
				(type default)
			)
			(layer "F.Fab")
		)
		(fp_line
			(start 0.67945 -0.3048)
			(end 0.67945 0.3048)
			(stroke
				(width 0.1)
				(type default)
			)
			(layer "F.Fab")
		)
		(fp_line
			(start -0.67945 -0.305054)
			(end -0.12065 -0.305054)
			(stroke
				(width 0.1)
				(type default)
			)
			(layer "F.Fab")
		)
		(fp_line
			(start -0.12065 -0.305054)
			(end -0.12065 -0.2794)
			(stroke
				(width 0.1)
				(type default)
			)
			(layer "F.Fab")
		)
		(pad "1" smd circle
			(at -0.40005 0 270)
			(size 0 0)
			(layers "F.Cu" "F.Mask" "F.Paste")
			(net "SPI_BIC1_CS0_LS23_R1_N")
		)
		(pad "2" smd circle
			(at 0.40005 0 270)
			(size 0 0)
			(layers "F.Cu" "F.Mask" "F.Paste")
			(net "SPI_BIC1_CS0_LS23_R_N")
		)
	)
	(footprint ""
		(layer "F.Cu")
		(at 258.362196 -262.645652 90)
		(property "Reference" "C3420"
			(at 0 0 90)
			(layer "F.SilkS")
			(hide yes)
			(effects
				(font
					(size 1.27 1.27)
				)
			)
		)
		(property "Value" ""
			(at 0 0 90)
			(layer "F.Fab")
			(effects
				(font
					(size 1.27 1.27)
				)
			)
		)
		(duplicate_pad_numbers_are_jumpers no)
		(fp_line
			(start 0.299974 -0.150114)
			(end 0.299974 0.150114)
			(stroke
				(width 0.1)
				(type default)
			)
			(layer "F.Fab")
		)
		(fp_line
			(start -0.299974 -0.150114)
			(end 0.299974 -0.150114)
			(stroke
				(width 0.1)
				(type default)
			)
			(layer "F.Fab")
		)
		(fp_line
			(start 0.299974 0.150114)
			(end -0.299974 0.150114)
			(stroke
				(width 0.1)
				(type default)
			)
			(layer "F.Fab")
		)
		(fp_line
			(start -0.299974 0.150114)
			(end -0.299974 -0.150114)
			(stroke
				(width 0.1)
				(type default)
			)
			(layer "F.Fab")
		)
		(pad "1" smd rect
			(at -0.2667 0 90)
			(size 0.3048 0.381)
			(layers "F.Cu" "F.Mask" "F.Paste")
			(net "P1V8_VDDA_PEX2")
		)
		(pad "2" smd rect
			(at 0.2667 0 90)
			(size 0.3048 0.381)
			(layers "F.Cu" "F.Mask" "F.Paste")
			(net "GND")
		)
	)
	(footprint ""
		(layer "F.Cu")
		(at 214.616284 -231.150922 90)
		(property "Reference" "R6361"
			(at 0 0 90)
			(layer "F.SilkS")
			(hide yes)
			(effects
				(font
					(size 1.27 1.27)
				)
			)
		)
		(property "Value" ""
			(at 0 0 90)
			(layer "F.Fab")
			(effects
				(font
					(size 1.27 1.27)
				)
			)
		)
		(duplicate_pad_numbers_are_jumpers no)
		(fp_line
			(start 0.7874 -0.4064)
			(end 0.7874 0.4064)
			(stroke
				(width 0.1524)
				(type default)
			)
			(layer "F.SilkS")
		)
		(fp_line
			(start -0.7874 -0.4064)
			(end 0.7874 -0.4064)
			(stroke
				(width 0.1524)
				(type default)
			)
			(layer "F.SilkS")
		)
		(fp_line
			(start 0.7874 0.4064)
			(end -0.7874 0.4064)
			(stroke
				(width 0.1524)
				(type default)
			)
			(layer "F.SilkS")
		)
		(fp_line
			(start -0.7874 0.4064)
			(end -0.7874 -0.4064)
			(stroke
				(width 0.1524)
				(type default)
			)
			(layer "F.SilkS")
		)
		(fp_line
			(start -0.12065 -0.305054)
			(end -0.12065 -0.2794)
			(stroke
				(width 0.1)
				(type default)
			)
			(layer "F.Fab")
		)
		(fp_line
			(start -0.67945 -0.305054)
			(end -0.12065 -0.305054)
			(stroke
				(width 0.1)
				(type default)
			)
			(layer "F.Fab")
		)
		(fp_line
			(start 0.67945 -0.3048)
			(end 0.67945 0.3048)
			(stroke
				(width 0.1)
				(type default)
			)
			(layer "F.Fab")
		)
		(fp_line
			(start 0.12065 -0.3048)
			(end 0.67945 -0.3048)
			(stroke
				(width 0.1)
				(type default)
			)
			(layer "F.Fab")
		)
		(fp_line
			(start 0.12065 -0.2794)
			(end 0.12065 -0.3048)
			(stroke
				(width 0.1)
				(type default)
			)
			(layer "F.Fab")
		)
		(fp_line
			(start -0.12065 -0.2794)
			(end 0.12065 -0.2794)
			(stroke
				(width 0.1)
				(type default)
			)
			(layer "F.Fab")
		)
		(fp_line
			(start 0.120396 0.2794)
			(end -0.12065 0.2794)
			(stroke
				(width 0.1)
				(type default)
			)
			(layer "F.Fab")
		)
		(fp_line
			(start -0.12065 0.2794)
			(end -0.12065 0.3048)
			(stroke
				(width 0.1)
				(type default)
			)
			(layer "F.Fab")
		)
		(fp_line
			(start 0.67945 0.3048)
			(end 0.120396 0.3048)
			(stroke
				(width 0.1)
				(type default)
			)
			(layer "F.Fab")
		)
		(fp_line
			(start 0.120396 0.3048)
			(end 0.120396 0.2794)
			(stroke
				(width 0.1)
				(type default)
			)
			(layer "F.Fab")
		)
		(fp_line
			(start -0.12065 0.3048)
			(end -0.67945 0.3048)
			(stroke
				(width 0.1)
				(type default)
			)
			(layer "F.Fab")
		)
		(fp_line
			(start -0.67945 0.3048)
			(end -0.67945 -0.305054)
			(stroke
				(width 0.1)
				(type default)
			)
			(layer "F.Fab")
		)
		(pad "1" smd circle
			(at -0.40005 0 90)
			(size 0 0)
			(layers "F.Cu" "F.Mask" "F.Paste")
			(net "RST_PEX_MUX_N")
		)
		(pad "2" smd circle
			(at 0.40005 0 90)
			(size 0 0)
			(layers "F.Cu" "F.Mask" "F.Paste")
			(net "RST_PEX_MUX_R_N")
		)
	)
	(footprint ""
		(layer "F.Cu")
		(at 76.891642 -343.952322 90)
		(property "Reference" "C113"
			(at 0 0 90)
			(layer "F.SilkS")
			(hide yes)
			(effects
				(font
					(size 1.27 1.27)
				)
			)
		)
		(property "Value" ""
			(at 0 0 90)
			(layer "F.Fab")
			(effects
				(font
					(size 1.27 1.27)
				)
			)
		)
		(duplicate_pad_numbers_are_jumpers no)
		(fp_line
			(start 0.299974 -0.150114)
			(end 0.299974 0.150114)
			(stroke
				(width 0.1)
				(type default)
			)
			(layer "F.Fab")
		)
		(fp_line
			(start -0.299974 -0.150114)
			(end 0.299974 -0.150114)
			(stroke
				(width 0.1)
				(type default)
			)
			(layer "F.Fab")
		)
		(fp_line
			(start 0.299974 0.150114)
			(end -0.299974 0.150114)
			(stroke
				(width 0.1)
				(type default)
			)
			(layer "F.Fab")
		)
		(fp_line
			(start -0.299974 0.150114)
			(end -0.299974 -0.150114)
			(stroke
				(width 0.1)
				(type default)
			)
			(layer "F.Fab")
		)
		(pad "1" smd rect
			(at -0.2667 0 90)
			(size 0.3048 0.381)
			(layers "F.Cu" "F.Mask" "F.Paste")
			(net "P5E_PEX0_STN5_TX_DP<87>")
		)
		(pad "2" smd rect
			(at 0.2667 0 90)
			(size 0.3048 0.381)
			(layers "F.Cu" "F.Mask" "F.Paste")
			(net "P5E_PEX0_STN5_TX_C_DP<87>")
		)
	)
)
